# BASEBOARD_FAB2 (Tioga Pass) — schematic netlist excerpt (pin names and nets, part order shuffled) for the footprints in the layout excerpt that follows; sources: Cadence DE-HDL packaged netlist, KiCad conversion of Wiwynn_Tioga_Pass_MB.brd

C1F19  CAP_A  0.01UF 25V 10% X7R  pkg 0402V  page 100 : A = M_G_CPU_VREF ; B = GND
C6B14  CAP  0.22UF 16V 10% X7R  pkg 0402  page 105 : A = P3E_CPU0_PE1_PCH_TXN<11> ; B = P3E_CPU0_PE1_PCH_C_TXN<11>
C1G24  CAP  220PF 50V 10% X7R  pkg 0402LF  page 223 : A = A_TSENSE_PVDDQ_GHJ ; B = GND

(kicad_pcb
	(version 20260206)
	(generator "pcbnew")
	(generator_version "10.0")
	(general
		(thickness 1.6)
		(legacy_teardrops no)
	)
	(paper "A4")
	(title_block
		(title "Wiwynn_Tioga_Pass_MB.brd")
		(comment 1 "Tioga Pass / footprints 1689-1691 of 4770")
	)
	(layers
		(0 "F.Cu" signal "TOP")
		(4 "In1.Cu" signal "L2GND")
		(6 "In2.Cu" signal "L3")
		(8 "In3.Cu" signal "L4GND")
		(10 "In4.Cu" signal "L5")
		(12 "In5.Cu" signal "L6GND")
		(14 "In6.Cu" signal "L7VCC")
		(16 "In7.Cu" signal "L8VCC")
		(18 "In8.Cu" signal "L9GND")
		(20 "In9.Cu" signal "L10")
		(22 "In10.Cu" signal "L11GND")
		(24 "In11.Cu" signal "L12")
		(26 "In12.Cu" signal "L13GND")
		(2 "B.Cu" signal "BOTTOM")
		(9 "F.Adhes" user "F.Adhesive")
		(11 "B.Adhes" user "B.Adhesive")
		(13 "F.Paste" user "Package Geometry/Pastemask Top")
		(15 "B.Paste" user "Package Geometry/Pastemask Bottom")
		(5 "F.SilkS" user "Ref Des/Silkscreen Top")
		(7 "B.SilkS" user "Ref Des/Silkscreen Bottom")
		(1 "F.Mask" user "Board Geometry/Soldermask Top")
		(3 "B.Mask" user "Board Geometry/Soldermask Bottom")
		(17 "Dwgs.User" user "User.Drawings")
		(19 "Cmts.User" user "User.Comments")
		(21 "Eco1.User" user "User.Eco1")
		(23 "Eco2.User" user "User.Eco2")
		(25 "Edge.Cuts" user "Board Geometry/Outline")
		(27 "Margin" user)
		(31 "F.CrtYd" user "Package Geometry/Place Bound Top")
		(29 "B.CrtYd" user "Package Geometry/Place Bound Bottom")
		(35 "F.Fab" user "Ref Des/Assembly Top")
		(33 "B.Fab" user "Ref Des/Assembly Bottom")
	)
	(footprint ""
		(layer "F.Cu")
		(at 323.0245 -117.222016 90)
		(property "Reference" "C6B14"
			(at -0.8382 -0.67818 90)
			(unlocked yes)
			(layer "F.SilkS")
			(effects
				(font
					(size 0.4064 0.254)
					(thickness 0.1524)
				)
				(justify left)
			)
		)
		(property "Value" ""
			(at 0 0 90)
			(layer "F.Fab")
			(effects
				(font
					(size 1.27 1.27)
				)
			)
		)
		(duplicate_pad_numbers_are_jumpers no)
		(fp_poly
			(pts
				(xy 0.3048 -0.1016) (xy 0.3048 0.9906) (xy -0.3048 0.9906) (xy -0.3048 -0.1016)
			)
			(stroke
				(width 0)
				(type default)
			)
			(fill no)
			(layer "F.CrtYd")
		)
		(fp_line
			(start 0.3048 -0.1016)
			(end -0.3048 -0.1016)
			(stroke
				(width 0.1)
				(type default)
			)
			(layer "F.Fab")
		)
		(fp_line
			(start -0.3048 -0.1016)
			(end -0.3048 0.9906)
			(stroke
				(width 0.1)
				(type default)
			)
			(layer "F.Fab")
		)
		(fp_line
			(start 0.3048 0.9906)
			(end 0.3048 -0.1016)
			(stroke
				(width 0.1)
				(type default)
			)
			(layer "F.Fab")
		)
		(fp_line
			(start -0.3048 0.9906)
			(end 0.3048 0.9906)
			(stroke
				(width 0.1)
				(type default)
			)
			(layer "F.Fab")
		)
		(pad "1" smd rect
			(at 0 0 90)
			(size 0.508 0.508)
			(layers "F.Cu" "F.Mask" "F.Paste")
			(net "P3E_CPU0_PE1_PCH_TXN<11>")
		)
		(pad "2" smd rect
			(at 0 0.889 90)
			(size 0.508 0.508)
			(layers "F.Cu" "F.Mask" "F.Paste")
			(net "P3E_CPU0_PE1_PCH_C_TXN<11>")
		)
		(zone
			(layer "F.Cu")
			(hatch none 0.5)
			(connect_pads
				(clearance 0)
			)
			(min_thickness 0.25)
			(keepout
				(tracks allowed)
				(vias not_allowed)
				(pads allowed)
				(copperpour not_allowed)
				(footprints allowed)
			)
			(placement
				(enabled no)
				(sheetname "")
			)
			(fill
				(thermal_gap 0.5)
				(thermal_bridge_width 0.5)
				(island_removal_mode 0)
			)
			(polygon
				(pts
					(xy 323.2785 -116.968016) (xy 323.2785 -117.476016) (xy 323.6595 -117.476016) (xy 323.6595 -116.968016)
				)
			)
		)
		(zone
			(layer "F.Cu")
			(hatch none 0.5)
			(connect_pads
				(clearance 0)
			)
			(min_thickness 0.25)
			(keepout
				(tracks not_allowed)
				(vias allowed)
				(pads allowed)
				(copperpour not_allowed)
				(footprints allowed)
			)
			(placement
				(enabled no)
				(sheetname "")
			)
			(fill
				(thermal_gap 0.5)
				(thermal_bridge_width 0.5)
				(island_removal_mode 0)
			)
			(polygon
				(pts
					(xy 323.6595 -116.968016) (xy 323.6595 -117.476016) (xy 323.2785 -117.476016) (xy 323.2785 -116.968016)
				)
			)
		)
	)
	(footprint ""
		(layer "F.Cu")
		(at 27.451558 -22.952456)
		(property "Reference" "C1F19"
			(at 0 0 0)
			(layer "F.SilkS")
			(hide yes)
			(effects
				(font
					(size 1.27 1.27)
				)
			)
		)
		(property "Value" ""
			(at 0 0 0)
			(layer "F.Fab")
			(effects
				(font
					(size 1.27 1.27)
				)
			)
		)
		(duplicate_pad_numbers_are_jumpers no)
		(fp_poly
			(pts
				(xy 0.3048 -0.1016) (xy 0.3048 0.9906) (xy -0.3048 0.9906) (xy -0.3048 -0.1016)
			)
			(stroke
				(width 0)
				(type default)
			)
			(fill no)
			(layer "F.CrtYd")
		)
		(fp_line
			(start -0.3048 -0.1016)
			(end -0.3048 0.9906)
			(stroke
				(width 0.1)
				(type default)
			)
			(layer "F.Fab")
		)
		(fp_line
			(start -0.3048 0.9906)
			(end 0.3048 0.9906)
			(stroke
				(width 0.1)
				(type default)
			)
			(layer "F.Fab")
		)
		(fp_line
			(start 0.3048 -0.1016)
			(end -0.3048 -0.1016)
			(stroke
				(width 0.1)
				(type default)
			)
			(layer "F.Fab")
		)
		(fp_line
			(start 0.3048 0.9906)
			(end 0.3048 -0.1016)
			(stroke
				(width 0.1)
				(type default)
			)
			(layer "F.Fab")
		)
		(pad "1" smd rect
			(at 0 0)
			(size 0.508 0.508)
			(layers "F.Cu" "F.Mask" "F.Paste")
			(net "M_G_CPU_VREF")
		)
		(pad "2" smd rect
			(at 0 0.889)
			(size 0.508 0.508)
			(layers "F.Cu" "F.Mask" "F.Paste")
			(net "GND")
		)
		(zone
			(layer "F.Cu")
			(hatch none 0.5)
			(connect_pads
				(clearance 0)
			)
			(min_thickness 0.25)
			(keepout
				(tracks allowed)
				(vias not_allowed)
				(pads allowed)
				(copperpour not_allowed)
				(footprints allowed)
			)
			(placement
				(enabled no)
				(sheetname "")
			)
			(fill
				(thermal_gap 0.5)
				(thermal_bridge_width 0.5)
				(island_removal_mode 0)
			)
			(polygon
				(pts
					(xy 27.197558 -22.698456) (xy 27.705558 -22.698456) (xy 27.705558 -22.317456) (xy 27.197558 -22.317456)
				)
			)
		)
		(zone
			(layer "F.Cu")
			(hatch none 0.5)
			(connect_pads
				(clearance 0)
			)
			(min_thickness 0.25)
			(keepout
				(tracks not_allowed)
				(vias allowed)
				(pads allowed)
				(copperpour not_allowed)
				(footprints allowed)
			)
			(placement
				(enabled no)
				(sheetname "")
			)
			(fill
				(thermal_gap 0.5)
				(thermal_bridge_width 0.5)
				(island_removal_mode 0)
			)
			(polygon
				(pts
					(xy 27.197558 -22.317456) (xy 27.705558 -22.317456) (xy 27.705558 -22.698456) (xy 27.197558 -22.698456)
				)
			)
		)
	)
	(footprint ""
		(layer "F.Cu")
		(at 7.333234 4.307332)
		(property "Reference" "C1G24"
			(at 0 0 0)
			(layer "F.SilkS")
			(hide yes)
			(effects
				(font
					(size 1.27 1.27)
				)
			)
		)
		(property "Value" ""
			(at 0 0 0)
			(layer "F.Fab")
			(effects
				(font
					(size 1.27 1.27)
				)
			)
		)
		(duplicate_pad_numbers_are_jumpers no)
		(fp_rect
			(start -0.3048 -0.1016)
			(end 0.3048 0.9906)
			(stroke
				(width 0)
				(type default)
			)
			(fill no)
			(layer "F.CrtYd")
		)
		(fp_line
			(start -0.3048 -0.1016)
			(end -0.3048 0.9906)
			(stroke
				(width 0.1)
				(type default)
			)
			(layer "F.Fab")
		)
		(fp_line
			(start -0.3048 0.9906)
			(end 0.3048 0.9906)
			(stroke
				(width 0.1)
				(type default)
			)
			(layer "F.Fab")
		)
		(fp_line
			(start 0.3048 -0.1016)
			(end -0.3048 -0.1016)
			(stroke
				(width 0.1)
				(type default)
			)
			(layer "F.Fab")
		)
		(fp_line
			(start 0.3048 0.9906)
			(end 0.3048 -0.1016)
			(stroke
				(width 0.1)
				(type default)
			)
			(layer "F.Fab")
		)
		(pad "1" smd rect
			(at 0 0)
			(size 0.508 0.508)
			(layers "F.Cu" "F.Mask" "F.Paste")
			(net "A_TSENSE_PVDDQ_GHJ")
		)
		(pad "2" smd rect
			(at 0 0.889)
			(size 0.508 0.508)
			(layers "F.Cu" "F.Mask" "F.Paste")
			(net "GND")
		)
		(zone
			(layer "F.Cu")
			(hatch none 0.5)
			(connect_pads
				(clearance 0)
			)
			(min_thickness 0.25)
			(keepout
				(tracks allowed)
				(vias not_allowed)
				(pads allowed)
				(copperpour not_allowed)
				(footprints allowed)
			)
			(placement
				(enabled no)
				(sheetname "")
			)
			(fill
				(thermal_gap 0.5)
				(thermal_bridge_width 0.5)
				(island_removal_mode 0)
			)
			(polygon
				(pts
					(xy 7.079234 4.561332) (xy 7.079234 4.942332) (xy 7.587234 4.942332) (xy 7.587234 4.561332)
				)
			)
		)
		(zone
			(layer "F.Cu")
			(hatch none 0.5)
			(connect_pads
				(clearance 0)
			)
			(min_thickness 0.25)
			(keepout
				(tracks not_allowed)
				(vias allowed)
				(pads allowed)
				(copperpour not_allowed)
				(footprints allowed)
			)
			(placement
				(enabled no)
				(sheetname "")
			)
			(fill
				(thermal_gap 0.5)
				(thermal_bridge_width 0.5)
				(island_removal_mode 0)
			)
			(polygon
				(pts
					(xy 7.079234 4.561332) (xy 7.079234 4.942332) (xy 7.587234 4.942332) (xy 7.587234 4.561332)
				)
			)
		)
	)
)
